# S9S_MB_2U (Grand Teton) — schematic netlist excerpt (pin names and nets, part order shuffled) for the footprints in the layout excerpt that follows; sources: Cadence DE-HDL packaged netlist, KiCad conversion of 03242023_DA0F0TMBIJ0_F0T_Motherboard_J_brd_V01_OCP.brd

PR2535  Q_RES  10 1% EMPTY  pkg 0402LF  page 304 : A = P12V_HSC_GATE_G5 ; B = P12V_HSC_GATE2
PR215  Q_RES  1K 1% CHIP  pkg 0402LF  page 296 : A = P3V3_AUX ; B = PVCCD_HV_CPU1_PIN_ALT

(kicad_pcb
	(version 20260206)
	(generator "pcbnew")
	(generator_version "10.0")
	(general
		(thickness 1.6)
		(legacy_teardrops no)
	)
	(paper "A4")
	(title_block
		(title "03242023_DA0F0TMBIJ0_F0T_Motherboard_J_brd_V01_OCP.brd")
		(comment 1 "Grand Teton / footprints 1496-1497 of 6105")
	)
	(layers
		(0 "F.Cu" signal "TOP")
		(4 "In1.Cu" signal "GND")
		(6 "In2.Cu" signal "IN1")
		(8 "In3.Cu" signal "GND1")
		(10 "In4.Cu" signal "IN2")
		(12 "In5.Cu" signal "GND2")
		(14 "In6.Cu" signal "IN3")
		(16 "In7.Cu" signal "GND3")
		(18 "In8.Cu" signal "VCC")
		(20 "In9.Cu" signal "VCC1")
		(22 "In10.Cu" signal "GND4")
		(24 "In11.Cu" signal "IN4")
		(26 "In12.Cu" signal "GND5")
		(28 "In13.Cu" signal "IN5")
		(30 "In14.Cu" signal "GND6")
		(32 "In15.Cu" signal "IN6")
		(34 "In16.Cu" signal "GND7")
		(2 "B.Cu" signal "BOTTOM")
		(9 "F.Adhes" user "F.Adhesive")
		(11 "B.Adhes" user "B.Adhesive")
		(13 "F.Paste" user "Package Geometry/Pastemask Top")
		(15 "B.Paste" user "Package Geometry/Pastemask Bottom")
		(5 "F.SilkS" user "Ref Des/Silkscreen Top")
		(7 "B.SilkS" user "Ref Des/Silkscreen Bottom")
		(1 "F.Mask" user "Board Geometry/Soldermask Top")
		(3 "B.Mask" user "Board Geometry/Soldermask Bottom")
		(17 "Dwgs.User" user "User.Drawings")
		(19 "Cmts.User" user "User.Comments")
		(21 "Eco1.User" user "User.Eco1")
		(23 "Eco2.User" user "User.Eco2")
		(25 "Edge.Cuts" user "Board Geometry/Outline")
		(27 "Margin" user)
		(31 "F.CrtYd" user "Package Geometry/Place Bound Top")
		(29 "B.CrtYd" user "Package Geometry/Place Bound Bottom")
		(35 "F.Fab" user "Ref Des/Assembly Top")
		(33 "B.Fab" user "Ref Des/Assembly Bottom")
	)
	(footprint ""
		(layer "F.Cu")
		(at 22.13356 -166.767256)
		(property "Reference" "PR215"
			(at 0 0 0)
			(layer "F.SilkS")
			(hide yes)
			(effects
				(font
					(size 1.27 1.27)
				)
			)
		)
		(property "Value" ""
			(at 0 0 0)
			(layer "F.Fab")
			(effects
				(font
					(size 1.27 1.27)
				)
			)
		)
		(duplicate_pad_numbers_are_jumpers no)
		(fp_line
			(start -0.7874 -0.4064)
			(end 0.7874 -0.4064)
			(stroke
				(width 0.1524)
				(type default)
			)
			(layer "F.SilkS")
		)
		(fp_line
			(start -0.7874 0.4064)
			(end -0.7874 -0.4064)
			(stroke
				(width 0.1524)
				(type default)
			)
			(layer "F.SilkS")
		)
		(fp_line
			(start 0.7874 -0.4064)
			(end 0.7874 0.4064)
			(stroke
				(width 0.1524)
				(type default)
			)
			(layer "F.SilkS")
		)
		(fp_line
			(start 0.7874 0.4064)
			(end -0.7874 0.4064)
			(stroke
				(width 0.1524)
				(type default)
			)
			(layer "F.SilkS")
		)
		(fp_line
			(start -0.67945 -0.305054)
			(end -0.12065 -0.305054)
			(stroke
				(width 0.1)
				(type default)
			)
			(layer "F.Fab")
		)
		(fp_line
			(start -0.67945 0.3048)
			(end -0.67945 -0.305054)
			(stroke
				(width 0.1)
				(type default)
			)
			(layer "F.Fab")
		)
		(fp_line
			(start -0.12065 -0.305054)
			(end -0.12065 -0.2794)
			(stroke
				(width 0.1)
				(type default)
			)
			(layer "F.Fab")
		)
		(fp_line
			(start -0.12065 -0.2794)
			(end 0.12065 -0.2794)
			(stroke
				(width 0.1)
				(type default)
			)
			(layer "F.Fab")
		)
		(fp_line
			(start -0.12065 0.2794)
			(end -0.12065 0.3048)
			(stroke
				(width 0.1)
				(type default)
			)
			(layer "F.Fab")
		)
		(fp_line
			(start -0.12065 0.3048)
			(end -0.67945 0.3048)
			(stroke
				(width 0.1)
				(type default)
			)
			(layer "F.Fab")
		)
		(fp_line
			(start 0.120396 0.2794)
			(end -0.12065 0.2794)
			(stroke
				(width 0.1)
				(type default)
			)
			(layer "F.Fab")
		)
		(fp_line
			(start 0.120396 0.3048)
			(end 0.120396 0.2794)
			(stroke
				(width 0.1)
				(type default)
			)
			(layer "F.Fab")
		)
		(fp_line
			(start 0.12065 -0.3048)
			(end 0.67945 -0.3048)
			(stroke
				(width 0.1)
				(type default)
			)
			(layer "F.Fab")
		)
		(fp_line
			(start 0.12065 -0.2794)
			(end 0.12065 -0.3048)
			(stroke
				(width 0.1)
				(type default)
			)
			(layer "F.Fab")
		)
		(fp_line
			(start 0.67945 -0.3048)
			(end 0.67945 0.3048)
			(stroke
				(width 0.1)
				(type default)
			)
			(layer "F.Fab")
		)
		(fp_line
			(start 0.67945 0.3048)
			(end 0.120396 0.3048)
			(stroke
				(width 0.1)
				(type default)
			)
			(layer "F.Fab")
		)
		(pad "1" smd circle
			(at -0.40005 0)
			(size 0 0)
			(layers "F.Cu" "F.Mask" "F.Paste")
			(net "P3V3_AUX")
		)
		(pad "2" smd circle
			(at 0.40005 0)
			(size 0 0)
			(layers "F.Cu" "F.Mask" "F.Paste")
			(net "PVCCD_HV_CPU1_PIN_ALT")
		)
	)
	(footprint ""
		(layer "F.Cu")
		(at 244.596666 -394.17117)
		(property "Reference" "PR2535"
			(at 0 0 0)
			(layer "F.SilkS")
			(hide yes)
			(effects
				(font
					(size 1.27 1.27)
				)
			)
		)
		(property "Value" ""
			(at 0 0 0)
			(layer "F.Fab")
			(effects
				(font
					(size 1.27 1.27)
				)
			)
		)
		(duplicate_pad_numbers_are_jumpers no)
		(fp_line
			(start -0.7874 -0.4064)
			(end 0.7874 -0.4064)
			(stroke
				(width 0.1524)
				(type default)
			)
			(layer "F.SilkS")
		)
		(fp_line
			(start -0.7874 0.4064)
			(end -0.7874 -0.4064)
			(stroke
				(width 0.1524)
				(type default)
			)
			(layer "F.SilkS")
		)
		(fp_line
			(start 0.7874 -0.4064)
			(end 0.7874 0.4064)
			(stroke
				(width 0.1524)
				(type default)
			)
			(layer "F.SilkS")
		)
		(fp_line
			(start 0.7874 0.4064)
			(end -0.7874 0.4064)
			(stroke
				(width 0.1524)
				(type default)
			)
			(layer "F.SilkS")
		)
		(fp_line
			(start -0.67945 -0.305054)
			(end -0.12065 -0.305054)
			(stroke
				(width 0.1)
				(type default)
			)
			(layer "F.Fab")
		)
		(fp_line
			(start -0.67945 0.3048)
			(end -0.67945 -0.305054)
			(stroke
				(width 0.1)
				(type default)
			)
			(layer "F.Fab")
		)
		(fp_line
			(start -0.12065 -0.305054)
			(end -0.12065 -0.2794)
			(stroke
				(width 0.1)
				(type default)
			)
			(layer "F.Fab")
		)
		(fp_line
			(start -0.12065 -0.2794)
			(end 0.12065 -0.2794)
			(stroke
				(width 0.1)
				(type default)
			)
			(layer "F.Fab")
		)
		(fp_line
			(start -0.12065 0.2794)
			(end -0.12065 0.3048)
			(stroke
				(width 0.1)
				(type default)
			)
			(layer "F.Fab")
		)
		(fp_line
			(start -0.12065 0.3048)
			(end -0.67945 0.3048)
			(stroke
				(width 0.1)
				(type default)
			)
			(layer "F.Fab")
		)
		(fp_line
			(start 0.120396 0.2794)
			(end -0.12065 0.2794)
			(stroke
				(width 0.1)
				(type default)
			)
			(layer "F.Fab")
		)
		(fp_line
			(start 0.120396 0.3048)
			(end 0.120396 0.2794)
			(stroke
				(width 0.1)
				(type default)
			)
			(layer "F.Fab")
		)
		(fp_line
			(start 0.12065 -0.3048)
			(end 0.67945 -0.3048)
			(stroke
				(width 0.1)
				(type default)
			)
			(layer "F.Fab")
		)
		(fp_line
			(start 0.12065 -0.2794)
			(end 0.12065 -0.3048)
			(stroke
				(width 0.1)
				(type default)
			)
			(layer "F.Fab")
		)
		(fp_line
			(start 0.67945 -0.3048)
			(end 0.67945 0.3048)
			(stroke
				(width 0.1)
				(type default)
			)
			(layer "F.Fab")
		)
		(fp_line
			(start 0.67945 0.3048)
			(end 0.120396 0.3048)
			(stroke
				(width 0.1)
				(type default)
			)
			(layer "F.Fab")
		)
		(pad "1" smd circle
			(at -0.40005 0)
			(size 0 0)
			(layers "F.Cu" "F.Mask" "F.Paste")
			(net "P12V_HSC_GATE_G5")
		)
		(pad "2" smd circle
			(at 0.40005 0)
			(size 0 0)
			(layers "F.Cu" "F.Mask" "F.Paste")
			(net "P12V_HSC_GATE2")
		)
	)
)
